# T6G (Grand Teton) — schematic netlist excerpt (pin names and nets, part order shuffled) for the footprints in the layout excerpt that follows; sources: Cadence DE-HDL packaged netlist, KiCad conversion of 04192023_DAF0TMB3IC0_F0TG_MB_C_brd_V02_OCP.brd

PC2210  Q_CAP  1UF 25V 10% X6S  pkg C0402  page 146 : A = P3V3_E1S_VCC_0 ; B = GND
R427  Q_RES  0 5% CHIP  pkg 0402LF  page 159 : A = I3C_0_SPD_DDRAF_CPU0_SDA ; B = I3C_0_SPD_DDRAF_CPU0_R_SDA

(kicad_pcb
	(version 20260206)
	(generator "pcbnew")
	(generator_version "10.0")
	(general
		(thickness 1.6)
		(legacy_teardrops no)
	)
	(paper "A4")
	(title_block
		(title "04192023_DAF0TMB3IC0_F0TG_MB_C_brd_V02_OCP.brd")
		(comment 1 "Grand Teton / footprints 3793-3794 of 8354")
	)
	(layers
		(0 "F.Cu" signal "TOP")
		(4 "In1.Cu" signal "GND")
		(6 "In2.Cu" signal "IN1")
		(8 "In3.Cu" signal "GND1")
		(10 "In4.Cu" signal "IN2")
		(12 "In5.Cu" signal "GND2")
		(14 "In6.Cu" signal "IN3")
		(16 "In7.Cu" signal "GND3")
		(18 "In8.Cu" signal "VCC")
		(20 "In9.Cu" signal "VCC1")
		(22 "In10.Cu" signal "GND4")
		(24 "In11.Cu" signal "IN4")
		(26 "In12.Cu" signal "GND5")
		(28 "In13.Cu" signal "IN5")
		(30 "In14.Cu" signal "GND6")
		(32 "In15.Cu" signal "IN6")
		(34 "In16.Cu" signal "GND7")
		(2 "B.Cu" signal "BOTTOM")
		(9 "F.Adhes" user "F.Adhesive")
		(11 "B.Adhes" user "B.Adhesive")
		(13 "F.Paste" user "Package Geometry/Pastemask Top")
		(15 "B.Paste" user "Package Geometry/Pastemask Bottom")
		(5 "F.SilkS" user "Ref Des/Silkscreen Top")
		(7 "B.SilkS" user "Ref Des/Silkscreen Bottom")
		(1 "F.Mask" user "Board Geometry/Soldermask Top")
		(3 "B.Mask" user "Board Geometry/Soldermask Bottom")
		(17 "Dwgs.User" user "User.Drawings")
		(19 "Cmts.User" user "User.Comments")
		(21 "Eco1.User" user "User.Eco1")
		(23 "Eco2.User" user "User.Eco2")
		(25 "Edge.Cuts" user "Board Geometry/Outline")
		(27 "Margin" user)
		(31 "F.CrtYd" user "Package Geometry/Place Bound Top")
		(29 "B.CrtYd" user "Package Geometry/Place Bound Bottom")
		(35 "F.Fab" user "Ref Des/Assembly Top")
		(33 "B.Fab" user "Ref Des/Assembly Bottom")
	)
	(footprint ""
		(layer "F.Cu")
		(at 219.974922 -73.484994 180)
		(property "Reference" "PC2210"
			(at 0 0 180)
			(layer "F.SilkS")
			(hide yes)
			(effects
				(font
					(size 1.27 1.27)
				)
			)
		)
		(property "Value" ""
			(at 0 0 180)
			(layer "F.Fab")
			(effects
				(font
					(size 1.27 1.27)
				)
			)
		)
		(duplicate_pad_numbers_are_jumpers no)
		(fp_line
			(start 0.7874 0.4064)
			(end -0.7874 0.4064)
			(stroke
				(width 0.1524)
				(type default)
			)
			(layer "F.SilkS")
		)
		(fp_line
			(start 0.7874 -0.4064)
			(end 0.7874 0.4064)
			(stroke
				(width 0.1524)
				(type default)
			)
			(layer "F.SilkS")
		)
		(fp_line
			(start -0.7874 0.4064)
			(end -0.7874 -0.4064)
			(stroke
				(width 0.1524)
				(type default)
			)
			(layer "F.SilkS")
		)
		(fp_line
			(start -0.7874 -0.4064)
			(end 0.7874 -0.4064)
			(stroke
				(width 0.1524)
				(type default)
			)
			(layer "F.SilkS")
		)
		(fp_line
			(start 0.67945 0.3048)
			(end 0.120396 0.3048)
			(stroke
				(width 0.1)
				(type default)
			)
			(layer "F.Fab")
		)
		(fp_line
			(start 0.67945 -0.3048)
			(end 0.67945 0.3048)
			(stroke
				(width 0.1)
				(type default)
			)
			(layer "F.Fab")
		)
		(fp_line
			(start 0.12065 -0.2794)
			(end 0.12065 -0.3048)
			(stroke
				(width 0.1)
				(type default)
			)
			(layer "F.Fab")
		)
		(fp_line
			(start 0.12065 -0.3048)
			(end 0.67945 -0.3048)
			(stroke
				(width 0.1)
				(type default)
			)
			(layer "F.Fab")
		)
		(fp_line
			(start 0.120396 0.3048)
			(end 0.120396 0.2794)
			(stroke
				(width 0.1)
				(type default)
			)
			(layer "F.Fab")
		)
		(fp_line
			(start 0.120396 0.2794)
			(end -0.12065 0.2794)
			(stroke
				(width 0.1)
				(type default)
			)
			(layer "F.Fab")
		)
		(fp_line
			(start -0.12065 0.3048)
			(end -0.67945 0.3048)
			(stroke
				(width 0.1)
				(type default)
			)
			(layer "F.Fab")
		)
		(fp_line
			(start -0.12065 0.2794)
			(end -0.12065 0.3048)
			(stroke
				(width 0.1)
				(type default)
			)
			(layer "F.Fab")
		)
		(fp_line
			(start -0.12065 -0.2794)
			(end 0.12065 -0.2794)
			(stroke
				(width 0.1)
				(type default)
			)
			(layer "F.Fab")
		)
		(fp_line
			(start -0.12065 -0.305054)
			(end -0.12065 -0.2794)
			(stroke
				(width 0.1)
				(type default)
			)
			(layer "F.Fab")
		)
		(fp_line
			(start -0.67945 0.3048)
			(end -0.67945 -0.305054)
			(stroke
				(width 0.1)
				(type default)
			)
			(layer "F.Fab")
		)
		(fp_line
			(start -0.67945 -0.305054)
			(end -0.12065 -0.305054)
			(stroke
				(width 0.1)
				(type default)
			)
			(layer "F.Fab")
		)
		(pad "1" smd circle
			(at -0.40005 0 180)
			(size 0 0)
			(layers "F.Cu" "F.Mask" "F.Paste")
			(net "P3V3_E1S_VCC_0")
		)
		(pad "2" smd circle
			(at 0.40005 0 180)
			(size 0 0)
			(layers "F.Cu" "F.Mask" "F.Paste")
			(net "GND")
		)
	)
	(footprint ""
		(layer "F.Cu")
		(at 319.22339 -192.89776 -90)
		(property "Reference" "R427"
			(at 0 0 270)
			(layer "F.SilkS")
			(hide yes)
			(effects
				(font
					(size 1.27 1.27)
				)
			)
		)
		(property "Value" ""
			(at 0 0 270)
			(layer "F.Fab")
			(effects
				(font
					(size 1.27 1.27)
				)
			)
		)
		(duplicate_pad_numbers_are_jumpers no)
		(fp_line
			(start -0.7874 0.4064)
			(end -0.7874 -0.4064)
			(stroke
				(width 0.1524)
				(type default)
			)
			(layer "F.SilkS")
		)
		(fp_line
			(start 0.7874 0.4064)
			(end -0.7874 0.4064)
			(stroke
				(width 0.1524)
				(type default)
			)
			(layer "F.SilkS")
		)
		(fp_line
			(start -0.7874 -0.4064)
			(end 0.7874 -0.4064)
			(stroke
				(width 0.1524)
				(type default)
			)
			(layer "F.SilkS")
		)
		(fp_line
			(start 0.7874 -0.4064)
			(end 0.7874 0.4064)
			(stroke
				(width 0.1524)
				(type default)
			)
			(layer "F.SilkS")
		)
		(fp_line
			(start -0.67945 0.3048)
			(end -0.67945 -0.305054)
			(stroke
				(width 0.1)
				(type default)
			)
			(layer "F.Fab")
		)
		(fp_line
			(start -0.12065 0.3048)
			(end -0.67945 0.3048)
			(stroke
				(width 0.1)
				(type default)
			)
			(layer "F.Fab")
		)
		(fp_line
			(start 0.120396 0.3048)
			(end 0.120396 0.2794)
			(stroke
				(width 0.1)
				(type default)
			)
			(layer "F.Fab")
		)
		(fp_line
			(start 0.67945 0.3048)
			(end 0.120396 0.3048)
			(stroke
				(width 0.1)
				(type default)
			)
			(layer "F.Fab")
		)
		(fp_line
			(start -0.12065 0.2794)
			(end -0.12065 0.3048)
			(stroke
				(width 0.1)
				(type default)
			)
			(layer "F.Fab")
		)
		(fp_line
			(start 0.120396 0.2794)
			(end -0.12065 0.2794)
			(stroke
				(width 0.1)
				(type default)
			)
			(layer "F.Fab")
		)
		(fp_line
			(start -0.12065 -0.2794)
			(end 0.12065 -0.2794)
			(stroke
				(width 0.1)
				(type default)
			)
			(layer "F.Fab")
		)
		(fp_line
			(start 0.12065 -0.2794)
			(end 0.12065 -0.3048)
			(stroke
				(width 0.1)
				(type default)
			)
			(layer "F.Fab")
		)
		(fp_line
			(start 0.12065 -0.3048)
			(end 0.67945 -0.3048)
			(stroke
				(width 0.1)
				(type default)
			)
			(layer "F.Fab")
		)
		(fp_line
			(start 0.67945 -0.3048)
			(end 0.67945 0.3048)
			(stroke
				(width 0.1)
				(type default)
			)
			(layer "F.Fab")
		)
		(fp_line
			(start -0.67945 -0.305054)
			(end -0.12065 -0.305054)
			(stroke
				(width 0.1)
				(type default)
			)
			(layer "F.Fab")
		)
		(fp_line
			(start -0.12065 -0.305054)
			(end -0.12065 -0.2794)
			(stroke
				(width 0.1)
				(type default)
			)
			(layer "F.Fab")
		)
		(pad "1" smd rect
			(at -0.40005 0 90)
			(size 0.4572 0.508)
			(layers "F.Cu" "F.Mask" "F.Paste")
			(net "I3C_0_SPD_DDRAF_CPU0_SDA")
		)
		(pad "2" smd rect
			(at 0.40005 0 90)
			(size 0.4572 0.508)
			(layers "F.Cu" "F.Mask" "F.Paste")
			(net "I3C_0_SPD_DDRAF_CPU0_R_SDA")
		)
	)
)
